# BASEBOARD_FAB2 (Tioga Pass) — schematic netlist excerpt (pin names and nets, part order shuffled) for the footprints in the layout excerpt that follows; sources: Cadence DE-HDL packaged netlist, KiCad conversion of Wiwynn_Tioga_Pass_MB.brd

CR7E1  DIODE  BAT54WS IC  pkg SMLF  page 196 : C = PWRGD_P3V3_STBY ; A = PWRGD_DSW_PWROK
R2R6  RES  51 5.0% CHIP  pkg 0402  page 191 : A = SGPIO_BMC_DIN_R ; B = SGPIO_BMC_DIN

(kicad_pcb
	(version 20260206)
	(generator "pcbnew")
	(generator_version "10.0")
	(general
		(thickness 1.6)
		(legacy_teardrops no)
	)
	(paper "A4")
	(title_block
		(title "Wiwynn_Tioga_Pass_MB.brd")
		(comment 1 "Tioga Pass / footprints 3536-3537 of 4770")
	)
	(layers
		(0 "F.Cu" signal "TOP")
		(4 "In1.Cu" signal "L2GND")
		(6 "In2.Cu" signal "L3")
		(8 "In3.Cu" signal "L4GND")
		(10 "In4.Cu" signal "L5")
		(12 "In5.Cu" signal "L6GND")
		(14 "In6.Cu" signal "L7VCC")
		(16 "In7.Cu" signal "L8VCC")
		(18 "In8.Cu" signal "L9GND")
		(20 "In9.Cu" signal "L10")
		(22 "In10.Cu" signal "L11GND")
		(24 "In11.Cu" signal "L12")
		(26 "In12.Cu" signal "L13GND")
		(2 "B.Cu" signal "BOTTOM")
		(9 "F.Adhes" user "F.Adhesive")
		(11 "B.Adhes" user "B.Adhesive")
		(13 "F.Paste" user "Package Geometry/Pastemask Top")
		(15 "B.Paste" user "Package Geometry/Pastemask Bottom")
		(5 "F.SilkS" user "Ref Des/Silkscreen Top")
		(7 "B.SilkS" user "Ref Des/Silkscreen Bottom")
		(1 "F.Mask" user "Board Geometry/Soldermask Top")
		(3 "B.Mask" user "Board Geometry/Soldermask Bottom")
		(17 "Dwgs.User" user "User.Drawings")
		(19 "Cmts.User" user "User.Comments")
		(21 "Eco1.User" user "User.Eco1")
		(23 "Eco2.User" user "User.Eco2")
		(25 "Edge.Cuts" user "Board Geometry/Outline")
		(27 "Margin" user)
		(31 "F.CrtYd" user "Package Geometry/Place Bound Top")
		(29 "B.CrtYd" user "Package Geometry/Place Bound Bottom")
		(35 "F.Fab" user "Ref Des/Assembly Top")
		(33 "B.Fab" user "Ref Des/Assembly Bottom")
	)
	(footprint ""
		(layer "B.Cu")
		(at 418.465 -4.191 90)
		(property "Reference" "CR7E1"
			(at 0 0 90)
			(layer "B.SilkS")
			(hide yes)
			(effects
				(font
					(size 1.27 1.27)
				)
				(justify mirror)
			)
		)
		(property "Value" ""
			(at 0 0 90)
			(layer "B.Fab")
			(effects
				(font
					(size 1.27 1.27)
				)
				(justify mirror)
			)
		)
		(duplicate_pad_numbers_are_jumpers no)
		(fp_line
			(start 1.335278 -0.291846)
			(end 1.335278 0.831596)
			(stroke
				(width 0.1524)
				(type default)
			)
			(layer "B.SilkS")
		)
		(fp_line
			(start 1.335278 0.831596)
			(end 0.854456 1.664462)
			(stroke
				(width 0.1524)
				(type default)
			)
			(layer "B.SilkS")
		)
		(fp_line
			(start 0.854456 0.831596)
			(end 1.8161 0.831596)
			(stroke
				(width 0.1524)
				(type default)
			)
			(layer "B.SilkS")
		)
		(fp_line
			(start 1.8161 1.664462)
			(end 1.335278 0.831596)
			(stroke
				(width 0.1524)
				(type default)
			)
			(layer "B.SilkS")
		)
		(fp_line
			(start 1.335278 1.664462)
			(end 1.8161 1.664462)
			(stroke
				(width 0.1524)
				(type default)
			)
			(layer "B.SilkS")
		)
		(fp_line
			(start 0.854456 1.664462)
			(end 1.335278 1.664462)
			(stroke
				(width 0.1524)
				(type default)
			)
			(layer "B.SilkS")
		)
		(fp_line
			(start 1.335278 2.576068)
			(end 1.335278 1.664462)
			(stroke
				(width 0.1524)
				(type default)
			)
			(layer "B.SilkS")
		)
		(fp_poly
			(pts
				(xy 0.67437 0.24384) (xy 0.67437 2.04216) (xy -0.67437 2.04216) (xy -0.67437 0.24384)
			)
			(stroke
				(width 0)
				(type default)
			)
			(fill no)
			(layer "B.CrtYd")
		)
		(fp_line
			(start 0.67437 0.24384)
			(end 0.67437 2.04216)
			(stroke
				(width 0.1)
				(type default)
			)
			(layer "B.Fab")
		)
		(fp_line
			(start -0.67437 0.24384)
			(end 0.67437 0.24384)
			(stroke
				(width 0.1)
				(type default)
			)
			(layer "B.Fab")
		)
		(fp_line
			(start 1.335278 0.831596)
			(end 1.335278 -0.291846)
			(stroke
				(width 0.1)
				(type default)
			)
			(layer "B.Fab")
		)
		(fp_line
			(start 1.335278 0.831596)
			(end 0.854456 1.664462)
			(stroke
				(width 0.1)
				(type default)
			)
			(layer "B.Fab")
		)
		(fp_line
			(start 0.854456 0.831596)
			(end 1.8161 0.831596)
			(stroke
				(width 0.1)
				(type default)
			)
			(layer "B.Fab")
		)
		(fp_line
			(start 1.8161 1.664462)
			(end 1.335278 0.831596)
			(stroke
				(width 0.1)
				(type default)
			)
			(layer "B.Fab")
		)
		(fp_line
			(start 1.335278 1.664462)
			(end 1.335278 2.576068)
			(stroke
				(width 0.1)
				(type default)
			)
			(layer "B.Fab")
		)
		(fp_line
			(start 0.854456 1.664462)
			(end 1.8161 1.664462)
			(stroke
				(width 0.1)
				(type default)
			)
			(layer "B.Fab")
		)
		(fp_line
			(start 0.67437 2.04216)
			(end -0.67437 2.04216)
			(stroke
				(width 0.1)
				(type default)
			)
			(layer "B.Fab")
		)
		(fp_line
			(start -0.67437 2.04216)
			(end -0.67437 0.24384)
			(stroke
				(width 0.1)
				(type default)
			)
			(layer "B.Fab")
		)
		(pad "1" smd rect
			(at 0 0 270)
			(size 0.4064 1.016)
			(layers "B.Cu" "B.Mask" "B.Paste")
			(net "PWRGD_P3V3_STBY")
		)
		(pad "2" smd rect
			(at 0 2.286 270)
			(size 0.4064 1.016)
			(layers "B.Cu" "B.Mask" "B.Paste")
			(net "PWRGD_DSW_PWROK")
		)
	)
	(footprint ""
		(layer "B.Cu")
		(at 373.888 -66.929)
		(property "Reference" "R2R6"
			(at 0 0 0)
			(layer "B.SilkS")
			(hide yes)
			(effects
				(font
					(size 1.27 1.27)
				)
				(justify mirror)
			)
		)
		(property "Value" ""
			(at 0 0 0)
			(layer "B.Fab")
			(effects
				(font
					(size 1.27 1.27)
				)
				(justify mirror)
			)
		)
		(duplicate_pad_numbers_are_jumpers no)
		(fp_poly
			(pts
				(xy 0.2794 -0.1016) (xy -0.2794 -0.1016) (xy -0.2794 0.9906) (xy 0.2794 0.9906)
			)
			(stroke
				(width 0)
				(type default)
			)
			(fill no)
			(layer "B.CrtYd")
		)
		(fp_line
			(start -0.2794 -0.1016)
			(end 0.2794 -0.1016)
			(stroke
				(width 0.1)
				(type default)
			)
			(layer "B.Fab")
		)
		(fp_line
			(start -0.2794 0.9906)
			(end -0.2794 -0.1016)
			(stroke
				(width 0.1)
				(type default)
			)
			(layer "B.Fab")
		)
		(fp_line
			(start 0.2794 -0.1016)
			(end 0.2794 0.9906)
			(stroke
				(width 0.1)
				(type default)
			)
			(layer "B.Fab")
		)
		(fp_line
			(start 0.2794 0.9906)
			(end -0.2794 0.9906)
			(stroke
				(width 0.1)
				(type default)
			)
			(layer "B.Fab")
		)
		(pad "1" smd rect
			(at 0 0 180)
			(size 0.508 0.508)
			(layers "B.Cu" "B.Mask" "B.Paste")
			(net "SGPIO_BMC_DIN_R")
		)
		(pad "2" smd rect
			(at 0 0.889 180)
			(size 0.508 0.508)
			(layers "B.Cu" "B.Mask" "B.Paste")
			(net "SGPIO_BMC_DIN")
		)
		(zone
			(layer "B.Cu")
			(hatch none 0.5)
			(connect_pads
				(clearance 0)
			)
			(min_thickness 0.25)
			(keepout
				(tracks allowed)
				(vias not_allowed)
				(pads allowed)
				(copperpour not_allowed)
				(footprints allowed)
			)
			(placement
				(enabled no)
				(sheetname "")
			)
			(fill
				(thermal_gap 0.5)
				(thermal_bridge_width 0.5)
				(island_removal_mode 0)
			)
			(polygon
				(pts
					(xy 374.142 -66.675) (xy 373.634 -66.675) (xy 373.634 -66.294) (xy 374.142 -66.294)
				)
			)
		)
		(zone
			(layer "B.Cu")
			(hatch none 0.5)
			(connect_pads
				(clearance 0)
			)
			(min_thickness 0.25)
			(keepout
				(tracks not_allowed)
				(vias allowed)
				(pads allowed)
				(copperpour not_allowed)
				(footprints allowed)
			)
			(placement
				(enabled no)
				(sheetname "")
			)
			(fill
				(thermal_gap 0.5)
				(thermal_bridge_width 0.5)
				(island_removal_mode 0)
			)
			(polygon
				(pts
					(xy 374.142 -66.294) (xy 373.634 -66.294) (xy 373.634 -66.675) (xy 374.142 -66.675)
				)
			)
		)
	)
)
